(kicad_pcb
	(version 20260206)
	(generator "pcbnew")
	(generator_version "10.0")
	(general
		(thickness 1.6)
		(legacy_teardrops no)
	)
	(paper "A4")
	(title_block
		(title "03242023_DA0F0TMBIJ0_F0T_Motherboard_J_brd_V01_OCP.brd")
		(comment 1 "Grand Teton / footprint 1682 of 6105 (U1), pads 2807-2917 of 4677")
	)
	(layers
		(0 "F.Cu" signal "TOP")
		(4 "In1.Cu" signal "GND")
		(6 "In2.Cu" signal "IN1")
		(8 "In3.Cu" signal "GND1")
		(10 "In4.Cu" signal "IN2")
		(12 "In5.Cu" signal "GND2")
		(14 "In6.Cu" signal "IN3")
		(16 "In7.Cu" signal "GND3")
		(18 "In8.Cu" signal "VCC")
		(20 "In9.Cu" signal "VCC1")
		(22 "In10.Cu" signal "GND4")
		(24 "In11.Cu" signal "IN4")
		(26 "In12.Cu" signal "GND5")
		(28 "In13.Cu" signal "IN5")
		(30 "In14.Cu" signal "GND6")
		(32 "In15.Cu" signal "IN6")
		(34 "In16.Cu" signal "GND7")
		(2 "B.Cu" signal "BOTTOM")
		(9 "F.Adhes" user "F.Adhesive")
		(11 "B.Adhes" user "B.Adhesive")
		(13 "F.Paste" user "Package Geometry/Pastemask Top")
		(15 "B.Paste" user "Package Geometry/Pastemask Bottom")
		(5 "F.SilkS" user "Ref Des/Silkscreen Top")
		(7 "B.SilkS" user "Ref Des/Silkscreen Bottom")
		(1 "F.Mask" user "Board Geometry/Soldermask Top")
		(3 "B.Mask" user "Board Geometry/Soldermask Bottom")
		(17 "Dwgs.User" user "User.Drawings")
		(19 "Cmts.User" user "User.Comments")
		(21 "Eco1.User" user "User.Eco1")
		(23 "Eco2.User" user "User.Eco2")
		(25 "Edge.Cuts" user "Board Geometry/Outline")
		(27 "Margin" user)
		(31 "F.CrtYd" user "Package Geometry/Place Bound Top")
		(29 "B.CrtYd" user "Package Geometry/Place Bound Bottom")
		(35 "F.Fab" user "Ref Des/Assembly Top")
		(33 "B.Fab" user "Ref Des/Assembly Bottom")
	)
	(footprint ""
		(layer "F.Cu")
		(at 111.93018 -251.76988 90)
		(property "Reference" "U1"
			(at -74.913236 41.548812 0)
			(unlocked yes)
			(layer "F.SilkS")
			(effects
				(font
					(size 1.6002 1.1938)
					(thickness 0.1524)
				)
				(justify left)
			)
		)
		(property "Value" ""
			(at 0 0 90)
			(layer "F.Fab")
			(effects
				(font
					(size 1.27 1.27)
				)
			)
		)
		(duplicate_pad_numbers_are_jumpers no)
		(pad "DK24" smd circle
			(at -18.705576 14.746732 270)
			(size 0.4318 0.4318)
			(layers "F.Cu" "F.Mask" "F.Paste")
			(net "GND")
		)
		(pad "DK26" smd circle
			(at -17.07769 14.746732 270)
			(size 0.4318 0.4318)
			(layers "F.Cu" "F.Mask" "F.Paste")
			(net "M_G_CPU1_SB_DQ<12>")
		)
		(pad "DK28" smd circle
			(at -15.450058 14.746732 270)
			(size 0.4318 0.4318)
			(layers "F.Cu" "F.Mask" "F.Paste")
			(net "M_G_CPU1_SB_DQ<9>")
		)
		(pad "DK30" smd circle
			(at -13.822426 14.746732 270)
			(size 0.4318 0.4318)
			(layers "F.Cu" "F.Mask" "F.Paste")
			(net "GND")
		)
		(pad "DK32" smd circle
			(at -12.19454 14.746732 270)
			(size 0.4318 0.4318)
			(layers "F.Cu" "F.Mask" "F.Paste")
			(net "M_G_CPU1_SB_DQ<4>")
		)
		(pad "DK34" smd circle
			(at -10.566654 14.746732 270)
			(size 0.4318 0.4318)
			(layers "F.Cu" "F.Mask" "F.Paste")
			(net "M_G_CPU1_SB_DQ<1>")
		)
		(pad "DK36" smd circle
			(at -8.939022 14.746732 270)
			(size 0.4318 0.4318)
			(layers "F.Cu" "F.Mask" "F.Paste")
			(net "GND")
		)
		(pad "DK38" smd circle
			(at -7.311136 14.746732 270)
			(size 0.4318 0.4318)
			(layers "F.Cu" "F.Mask" "F.Paste")
			(net "M_H_CPU1_SB_CS_N<2>")
		)
		(pad "DK40" smd circle
			(at -5.68325 14.746732 270)
			(size 0.4318 0.4318)
			(layers "F.Cu" "F.Mask" "F.Paste")
			(net "M_H_CPU1_SB_CA<4>")
		)
		(pad "DK42" smd circle
			(at -4.055618 14.746732 270)
			(size 0.4318 0.4318)
			(layers "F.Cu" "F.Mask" "F.Paste")
			(net "GND")
		)
		(pad "DK44" smd circle
			(at -2.427732 14.746732 270)
			(size 0.4318 0.4318)
			(layers "F.Cu" "F.Mask" "F.Paste")
			(net "M_G_CPU1_SA_CA<6>")
		)
		(pad "DK47" smd circle
			(at 1.613916 14.856714 270)
			(size 0.4318 0.4318)
			(layers "F.Cu" "F.Mask" "F.Paste")
			(net "M_F_CPU1_SB_RSP<1>")
		)
		(pad "DK49" smd circle
			(at 3.241802 14.856714 270)
			(size 0.4318 0.4318)
			(layers "F.Cu" "F.Mask" "F.Paste")
			(net "GND")
		)
		(pad "DK51" smd circle
			(at 4.869434 14.856714 270)
			(size 0.4318 0.4318)
			(layers "F.Cu" "F.Mask" "F.Paste")
			(net "M_G_CPU1_SA_CA<2>")
		)
		(pad "DK53" smd circle
			(at 6.49732 14.856714 270)
			(size 0.4318 0.4318)
			(layers "F.Cu" "F.Mask" "F.Paste")
			(net "M_G_CPU1_SA_CS_N<3>")
		)
		(pad "DK55" smd circle
			(at 8.124952 14.856714 270)
			(size 0.4318 0.4318)
			(layers "F.Cu" "F.Mask" "F.Paste")
			(net "GND")
		)
		(pad "DK57" smd circle
			(at 9.752838 14.856714 270)
			(size 0.4318 0.4318)
			(layers "F.Cu" "F.Mask" "F.Paste")
			(net "M_G_CPU1_SA_CB<4>")
		)
		(pad "DK59" smd circle
			(at 11.380724 14.856714 270)
			(size 0.4318 0.4318)
			(layers "F.Cu" "F.Mask" "F.Paste")
			(net "M_G_CPU1_SA_CB<1>")
		)
		(pad "DK61" smd circle
			(at 13.008356 14.856714 270)
			(size 0.4318 0.4318)
			(layers "F.Cu" "F.Mask" "F.Paste")
			(net "GND")
		)
		(pad "DK63" smd circle
			(at 14.635988 14.856714 270)
			(size 0.4318 0.4318)
			(layers "F.Cu" "F.Mask" "F.Paste")
			(net "M_G_CPU1_SA_DQ<28>")
		)
		(pad "DK65" smd circle
			(at 16.263874 14.856714 270)
			(size 0.4318 0.4318)
			(layers "F.Cu" "F.Mask" "F.Paste")
			(net "M_G_CPU1_SA_DQ<25>")
		)
		(pad "DK67" smd circle
			(at 17.89176 14.856714 270)
			(size 0.4318 0.4318)
			(layers "F.Cu" "F.Mask" "F.Paste")
			(net "GND")
		)
		(pad "DK69" smd circle
			(at 19.519392 14.856714 270)
			(size 0.4318 0.4318)
			(layers "F.Cu" "F.Mask" "F.Paste")
			(net "M_G_CPU1_SA_DQ<12>")
		)
		(pad "DK71" smd circle
			(at 21.147278 14.856714 270)
			(size 0.4318 0.4318)
			(layers "F.Cu" "F.Mask" "F.Paste")
			(net "M_G_CPU1_SA_DQ<9>")
		)
		(pad "DK73" smd circle
			(at 22.77491 14.856714 270)
			(size 0.4318 0.4318)
			(layers "F.Cu" "F.Mask" "F.Paste")
			(net "GND")
		)
		(pad "DK75" smd circle
			(at 24.402796 14.856714 270)
			(size 0.4318 0.4318)
			(layers "F.Cu" "F.Mask" "F.Paste")
			(net "M_H_CPU1_SA_DQ<4>")
		)
		(pad "DK77" smd circle
			(at 26.030682 14.856714 270)
			(size 0.4318 0.4318)
			(layers "F.Cu" "F.Mask" "F.Paste")
			(net "GND")
		)
		(pad "DK79" smd circle
			(at 27.658314 14.856714 270)
			(size 0.4318 0.4318)
			(layers "F.Cu" "F.Mask" "F.Paste")
			(net "GND")
		)
		(pad "DK81" smd circle
			(at 29.2862 14.856714 270)
			(size 0.4318 0.4318)
			(layers "F.Cu" "F.Mask" "F.Paste")
			(net "GND")
		)
		(pad "DK83" smd circle
			(at 30.914086 14.856714 270)
			(size 0.4318 0.4318)
			(layers "F.Cu" "F.Mask" "F.Paste")
			(net "GND")
		)
		(pad "DK85" smd circle
			(at 32.541718 14.856714 270)
			(size 0.4318 0.4318)
			(layers "F.Cu" "F.Mask" "F.Paste")
			(net "P5E_CPU1_PE3_TX_DN<7>")
		)
		(pad "DK87" smd circle
			(at 34.169604 14.856714 270)
			(size 0.4318 0.4318)
			(layers "F.Cu" "F.Mask" "F.Paste")
			(net "GND")
		)
		(pad "DK89" smd circle
			(at 35.797236 14.856714 270)
			(size 0.4318 0.4318)
			(layers "F.Cu" "F.Mask" "F.Paste")
			(net "P5E_CPU1_PE3_RX_DP<8>")
		)
		(pad "DK91" smd oval
			(at 37.425122 14.856714)
			(size 0.381 0.4826)
			(drill
				(offset 0 -0.0508)
			)
			(layers "F.Cu" "F.Mask" "F.Paste")
			(net "GND")
		)
		(pad "DL1" smd oval
			(at -37.425122 15.216886 180)
			(size 0.381 0.4826)
			(drill
				(offset 0 -0.0508)
			)
			(layers "F.Cu" "F.Mask" "F.Paste")
			(net "GND")
		)
		(pad "DL3" smd circle
			(at -35.797236 15.216886 270)
			(size 0.4318 0.4318)
			(layers "F.Cu" "F.Mask" "F.Paste")
			(net "UPI_CPU0_CPU1_P0P1_DN<8>")
		)
		(pad "DL5" smd circle
			(at -34.169604 15.216886 270)
			(size 0.4318 0.4318)
			(layers "F.Cu" "F.Mask" "F.Paste")
			(net "GND")
		)
		(pad "DL7" smd circle
			(at -32.541718 15.216886 270)
			(size 0.4318 0.4318)
			(layers "F.Cu" "F.Mask" "F.Paste")
			(net "UPI_CPU1_CPU0_P1P0_DN<7>")
		)
		(pad "DL9" smd circle
			(at -30.914086 15.216886 270)
			(size 0.4318 0.4318)
			(layers "F.Cu" "F.Mask" "F.Paste")
			(net "GND")
		)
		(pad "DL11" smd circle
			(at -29.2862 15.216886 270)
			(size 0.4318 0.4318)
			(layers "F.Cu" "F.Mask" "F.Paste")
			(net "P5E_CPU1_PE2_RX_DP<7>")
		)
		(pad "DL13" smd circle
			(at -27.658314 15.216886 270)
			(size 0.4318 0.4318)
			(layers "F.Cu" "F.Mask" "F.Paste")
			(net "GND")
		)
		(pad "DL15" smd circle
			(at -26.030682 15.216886 270)
			(size 0.4318 0.4318)
			(layers "F.Cu" "F.Mask" "F.Paste")
			(net "P5E_CPU1_PE2_TX_DP<7>")
		)
		(pad "DL17" smd circle
			(at -24.402796 15.216886 270)
			(size 0.4318 0.4318)
			(layers "F.Cu" "F.Mask" "F.Paste")
			(net "GND")
		)
		(pad "DL19" smd circle
			(at -22.77491 15.216886 270)
			(size 0.4318 0.4318)
			(layers "F.Cu" "F.Mask" "F.Paste")
			(net "M_H_CPU1_SB_DQ<21>")
		)
		(pad "DL21" smd circle
			(at -21.147278 15.216886 270)
			(size 0.4318 0.4318)
			(layers "F.Cu" "F.Mask" "F.Paste")
			(net "M_H_CPU1_SB_DQS_DN<2>")
		)
		(pad "DL23" smd circle
			(at -19.519392 15.216886 270)
			(size 0.4318 0.4318)
			(layers "F.Cu" "F.Mask" "F.Paste")
			(net "M_H_CPU1_SB_DQ<16>")
		)
		(pad "DL25" smd circle
			(at -17.89176 15.216886 270)
			(size 0.4318 0.4318)
			(layers "F.Cu" "F.Mask" "F.Paste")
			(net "M_G_CPU1_SB_DQ<13>")
		)
		(pad "DL27" smd circle
			(at -16.263874 15.216886 270)
			(size 0.4318 0.4318)
			(layers "F.Cu" "F.Mask" "F.Paste")
			(net "M_G_CPU1_SB_DQS_DP<1>")
		)
		(pad "DL29" smd circle
			(at -14.635988 15.216886 270)
			(size 0.4318 0.4318)
			(layers "F.Cu" "F.Mask" "F.Paste")
			(net "M_G_CPU1_SB_DQ<10>")
		)
		(pad "DL31" smd circle
			(at -13.008356 15.216886 270)
			(size 0.4318 0.4318)
			(layers "F.Cu" "F.Mask" "F.Paste")
			(net "M_G_CPU1_SB_DQ<5>")
		)
		(pad "DL33" smd circle
			(at -11.380724 15.216886 270)
			(size 0.4318 0.4318)
			(layers "F.Cu" "F.Mask" "F.Paste")
			(net "M_G_CPU1_SB_DQS_DP<0>")
		)
		(pad "DL35" smd circle
			(at -9.752838 15.216886 270)
			(size 0.4318 0.4318)
			(layers "F.Cu" "F.Mask" "F.Paste")
			(net "M_G_CPU1_SB_DQ<0>")
		)
		(pad "DL37" smd circle
			(at -8.124952 15.216886 270)
			(size 0.4318 0.4318)
			(layers "F.Cu" "F.Mask" "F.Paste")
			(net "M_H_CPU1_SB_CS_N<0>")
		)
		(pad "DL39" smd circle
			(at -6.49732 15.216886 270)
			(size 0.4318 0.4318)
			(layers "F.Cu" "F.Mask" "F.Paste")
			(net "GND")
		)
		(pad "DL41" smd circle
			(at -4.869434 15.216886 270)
			(size 0.4318 0.4318)
			(layers "F.Cu" "F.Mask" "F.Paste")
			(net "M_H_CPU1_SB_CA<2>")
		)
		(pad "DL43" smd circle
			(at -3.241802 15.216886 270)
			(size 0.4318 0.4318)
			(layers "F.Cu" "F.Mask" "F.Paste")
			(net "M_G_CPU1_SA_PAR")
		)
		(pad "DL45" smd circle
			(at -1.613916 15.216886 270)
			(size 0.4318 0.4318)
			(layers "F.Cu" "F.Mask" "F.Paste")
			(net "M_G_CPU1_CLK_DN<1>")
		)
		(pad "DL48" smd circle
			(at 2.427732 15.326868 270)
			(size 0.4318 0.4318)
			(layers "F.Cu" "F.Mask" "F.Paste")
			(net "M_F_CPU1_SB_RSP<0>")
		)
		(pad "DL50" smd circle
			(at 4.055618 15.326868 270)
			(size 0.4318 0.4318)
			(layers "F.Cu" "F.Mask" "F.Paste")
			(net "M_G_CPU1_SA_CA<4>")
		)
		(pad "DL52" smd circle
			(at 5.68325 15.326868 270)
			(size 0.4318 0.4318)
			(layers "F.Cu" "F.Mask" "F.Paste")
			(net "GND")
		)
		(pad "DL54" smd circle
			(at 7.311136 15.326868 270)
			(size 0.4318 0.4318)
			(layers "F.Cu" "F.Mask" "F.Paste")
			(net "M_G_CPU1_SA_CS_N<2>")
		)
		(pad "DL56" smd circle
			(at 8.939022 15.326868 270)
			(size 0.4318 0.4318)
			(layers "F.Cu" "F.Mask" "F.Paste")
			(net "M_G_CPU1_SA_CB<5>")
		)
		(pad "DL58" smd circle
			(at 10.566654 15.326868 270)
			(size 0.4318 0.4318)
			(layers "F.Cu" "F.Mask" "F.Paste")
			(net "M_G_CPU1_SA_DQS_DN<4>")
		)
		(pad "DL60" smd circle
			(at 12.19454 15.326868 270)
			(size 0.4318 0.4318)
			(layers "F.Cu" "F.Mask" "F.Paste")
			(net "M_G_CPU1_SA_CB<0>")
		)
		(pad "DL62" smd circle
			(at 13.822426 15.326868 270)
			(size 0.4318 0.4318)
			(layers "F.Cu" "F.Mask" "F.Paste")
			(net "M_G_CPU1_SA_DQ<29>")
		)
		(pad "DL64" smd circle
			(at 15.450058 15.326868 270)
			(size 0.4318 0.4318)
			(layers "F.Cu" "F.Mask" "F.Paste")
			(net "M_G_CPU1_SA_DQS_DN<3>")
		)
		(pad "DL66" smd circle
			(at 17.07769 15.326868 270)
			(size 0.4318 0.4318)
			(layers "F.Cu" "F.Mask" "F.Paste")
			(net "M_G_CPU1_SA_DQ<24>")
		)
		(pad "DL68" smd circle
			(at 18.705576 15.326868 270)
			(size 0.4318 0.4318)
			(layers "F.Cu" "F.Mask" "F.Paste")
			(net "M_G_CPU1_SA_DQ<13>")
		)
		(pad "DL70" smd circle
			(at 20.333462 15.326868 270)
			(size 0.4318 0.4318)
			(layers "F.Cu" "F.Mask" "F.Paste")
			(net "M_G_CPU1_SA_DQS_DP<1>")
		)
		(pad "DL72" smd circle
			(at 21.961094 15.326868 270)
			(size 0.4318 0.4318)
			(layers "F.Cu" "F.Mask" "F.Paste")
			(net "M_G_CPU1_SA_DQ<8>")
		)
		(pad "DL74" smd circle
			(at 23.58898 15.326868 270)
			(size 0.4318 0.4318)
			(layers "F.Cu" "F.Mask" "F.Paste")
			(net "M_H_CPU1_SA_DQ<5>")
		)
		(pad "DL76" smd circle
			(at 25.216612 15.326868 270)
			(size 0.4318 0.4318)
			(layers "F.Cu" "F.Mask" "F.Paste")
			(net "M_H_CPU1_SA_DQS_DP<0>")
		)
		(pad "DL78" smd circle
			(at 26.844498 15.326868 270)
			(size 0.4318 0.4318)
			(layers "F.Cu" "F.Mask" "F.Paste")
			(net "GND")
		)
		(pad "DL80" smd circle
			(at 28.472384 15.326868 270)
			(size 0.4318 0.4318)
			(layers "F.Cu" "F.Mask" "F.Paste")
			(net "Net_746")
		)
		(pad "DL82" smd circle
			(at 30.100016 15.326868 270)
			(size 0.4318 0.4318)
			(layers "F.Cu" "F.Mask" "F.Paste")
			(net "Net_723")
		)
		(pad "DL84" smd circle
			(at 31.727902 15.326868 270)
			(size 0.4318 0.4318)
			(layers "F.Cu" "F.Mask" "F.Paste")
			(net "GND")
		)
		(pad "DL86" smd circle
			(at 33.355534 15.326868 270)
			(size 0.4318 0.4318)
			(layers "F.Cu" "F.Mask" "F.Paste")
			(net "P5E_CPU1_PE3_TX_DP<7>")
		)
		(pad "DL88" smd circle
			(at 34.98342 15.326868 270)
			(size 0.4318 0.4318)
			(layers "F.Cu" "F.Mask" "F.Paste")
			(net "GND")
		)
		(pad "DL90" smd circle
			(at 36.611306 15.326868 270)
			(size 0.4318 0.4318)
			(layers "F.Cu" "F.Mask" "F.Paste")
			(net "P5E_CPU1_PE3_RX_DN<8>")
		)
		(pad "DM2" smd circle
			(at -36.611306 15.686532 270)
			(size 0.4318 0.4318)
			(layers "F.Cu" "F.Mask" "F.Paste")
			(net "UPI_CPU0_CPU1_P0P1_DP<8>")
		)
		(pad "DM4" smd circle
			(at -34.98342 15.686532 270)
			(size 0.4318 0.4318)
			(layers "F.Cu" "F.Mask" "F.Paste")
			(net "GND")
		)
		(pad "DM6" smd circle
			(at -33.355534 15.686532 270)
			(size 0.4318 0.4318)
			(layers "F.Cu" "F.Mask" "F.Paste")
			(net "UPI_CPU1_CPU0_P1P0_DP<7>")
		)
		(pad "DM8" smd circle
			(at -31.727902 15.686532 270)
			(size 0.4318 0.4318)
			(layers "F.Cu" "F.Mask" "F.Paste")
			(net "GND")
		)
		(pad "DM10" smd circle
			(at -30.100016 15.686532 270)
			(size 0.4318 0.4318)
			(layers "F.Cu" "F.Mask" "F.Paste")
			(net "P5E_CPU1_PE2_RX_DN<7>")
		)
		(pad "DM12" smd circle
			(at -28.472384 15.686532 270)
			(size 0.4318 0.4318)
			(layers "F.Cu" "F.Mask" "F.Paste")
			(net "GND")
		)
		(pad "DM14" smd circle
			(at -26.844498 15.686532 270)
			(size 0.4318 0.4318)
			(layers "F.Cu" "F.Mask" "F.Paste")
			(net "P5E_CPU1_PE2_TX_DP<8>")
		)
		(pad "DM16" smd circle
			(at -25.216612 15.686532 270)
			(size 0.4318 0.4318)
			(layers "F.Cu" "F.Mask" "F.Paste")
			(net "GND")
		)
		(pad "DM18" smd circle
			(at -23.58898 15.686532 270)
			(size 0.4318 0.4318)
			(layers "F.Cu" "F.Mask" "F.Paste")
			(net "GND")
		)
		(pad "DM20" smd circle
			(at -21.961094 15.686532 270)
			(size 0.4318 0.4318)
			(layers "F.Cu" "F.Mask" "F.Paste")
			(net "GND")
		)
		(pad "DM22" smd circle
			(at -20.333462 15.686532 270)
			(size 0.4318 0.4318)
			(layers "F.Cu" "F.Mask" "F.Paste")
			(net "GND")
		)
		(pad "DM24" smd circle
			(at -18.705576 15.686532 270)
			(size 0.4318 0.4318)
			(layers "F.Cu" "F.Mask" "F.Paste")
			(net "GND")
		)
		(pad "DM26" smd circle
			(at -17.07769 15.686532 270)
			(size 0.4318 0.4318)
			(layers "F.Cu" "F.Mask" "F.Paste")
			(net "GND")
		)
		(pad "DM28" smd circle
			(at -15.450058 15.686532 270)
			(size 0.4318 0.4318)
			(layers "F.Cu" "F.Mask" "F.Paste")
			(net "GND")
		)
		(pad "DM30" smd circle
			(at -13.822426 15.686532 270)
			(size 0.4318 0.4318)
			(layers "F.Cu" "F.Mask" "F.Paste")
			(net "GND")
		)
		(pad "DM32" smd circle
			(at -12.19454 15.686532 270)
			(size 0.4318 0.4318)
			(layers "F.Cu" "F.Mask" "F.Paste")
			(net "GND")
		)
		(pad "DM34" smd circle
			(at -10.566654 15.686532 270)
			(size 0.4318 0.4318)
			(layers "F.Cu" "F.Mask" "F.Paste")
			(net "GND")
		)
		(pad "DM36" smd circle
			(at -8.939022 15.686532 270)
			(size 0.4318 0.4318)
			(layers "F.Cu" "F.Mask" "F.Paste")
			(net "GND")
		)
		(pad "DM38" smd circle
			(at -7.311136 15.686532 270)
			(size 0.4318 0.4318)
			(layers "F.Cu" "F.Mask" "F.Paste")
			(net "GND")
		)
		(pad "DM40" smd circle
			(at -5.68325 15.686532 270)
			(size 0.4318 0.4318)
			(layers "F.Cu" "F.Mask" "F.Paste")
			(net "GND")
		)
		(pad "DM42" smd circle
			(at -4.055618 15.686532 270)
			(size 0.4318 0.4318)
			(layers "F.Cu" "F.Mask" "F.Paste")
			(net "GND")
		)
		(pad "DM44" smd circle
			(at -2.427732 15.686532 270)
			(size 0.4318 0.4318)
			(layers "F.Cu" "F.Mask" "F.Paste")
			(net "GND")
		)
		(pad "DM47" smd circle
			(at 1.613916 15.796514 270)
			(size 0.4318 0.4318)
			(layers "F.Cu" "F.Mask" "F.Paste")
			(net "GND")
		)
		(pad "DM49" smd circle
			(at 3.241802 15.796514 270)
			(size 0.4318 0.4318)
			(layers "F.Cu" "F.Mask" "F.Paste")
			(net "GND")
		)
		(pad "DM51" smd circle
			(at 4.869434 15.796514 270)
			(size 0.4318 0.4318)
			(layers "F.Cu" "F.Mask" "F.Paste")
			(net "GND")
		)
		(pad "DM53" smd circle
			(at 6.49732 15.796514 270)
			(size 0.4318 0.4318)
			(layers "F.Cu" "F.Mask" "F.Paste")
			(net "GND")
		)
		(pad "DM55" smd circle
			(at 8.124952 15.796514 270)
			(size 0.4318 0.4318)
			(layers "F.Cu" "F.Mask" "F.Paste")
			(net "GND")
		)
		(pad "DM57" smd circle
			(at 9.752838 15.796514 270)
			(size 0.4318 0.4318)
			(layers "F.Cu" "F.Mask" "F.Paste")
			(net "GND")
		)
		(pad "DM59" smd circle
			(at 11.380724 15.796514 270)
			(size 0.4318 0.4318)
			(layers "F.Cu" "F.Mask" "F.Paste")
			(net "GND")
		)
		(pad "DM61" smd circle
			(at 13.008356 15.796514 270)
			(size 0.4318 0.4318)
			(layers "F.Cu" "F.Mask" "F.Paste")
			(net "GND")
		)
		(pad "DM63" smd circle
			(at 14.635988 15.796514 270)
			(size 0.4318 0.4318)
			(layers "F.Cu" "F.Mask" "F.Paste")
			(net "GND")
		)
		(pad "DM65" smd circle
			(at 16.263874 15.796514 270)
			(size 0.4318 0.4318)
			(layers "F.Cu" "F.Mask" "F.Paste")
			(net "GND")
		)
	)
)
